(kicad_pcb
	(version 20260206)
	(generator "pcbnew")
	(generator_version "10.0")
	(general
		(thickness 1.6)
		(legacy_teardrops no)
	)
	(paper "A4")
	(title_block
		(title "03242023_DA0F0TMBIJ0_F0T_Motherboard_J_brd_V01_OCP.brd")
		(comment 1 "Grand Teton / footprints 3897-3899 of 6105")
	)
	(layers
		(0 "F.Cu" signal "TOP")
		(4 "In1.Cu" signal "GND")
		(6 "In2.Cu" signal "IN1")
		(8 "In3.Cu" signal "GND1")
		(10 "In4.Cu" signal "IN2")
		(12 "In5.Cu" signal "GND2")
		(14 "In6.Cu" signal "IN3")
		(16 "In7.Cu" signal "GND3")
		(18 "In8.Cu" signal "VCC")
		(20 "In9.Cu" signal "VCC1")
		(22 "In10.Cu" signal "GND4")
		(24 "In11.Cu" signal "IN4")
		(26 "In12.Cu" signal "GND5")
		(28 "In13.Cu" signal "IN5")
		(30 "In14.Cu" signal "GND6")
		(32 "In15.Cu" signal "IN6")
		(34 "In16.Cu" signal "GND7")
		(2 "B.Cu" signal "BOTTOM")
		(9 "F.Adhes" user "F.Adhesive")
		(11 "B.Adhes" user "B.Adhesive")
		(13 "F.Paste" user "Package Geometry/Pastemask Top")
		(15 "B.Paste" user "Package Geometry/Pastemask Bottom")
		(5 "F.SilkS" user "Ref Des/Silkscreen Top")
		(7 "B.SilkS" user "Ref Des/Silkscreen Bottom")
		(1 "F.Mask" user "Board Geometry/Soldermask Top")
		(3 "B.Mask" user "Board Geometry/Soldermask Bottom")
		(17 "Dwgs.User" user "User.Drawings")
		(19 "Cmts.User" user "User.Comments")
		(21 "Eco1.User" user "User.Eco1")
		(23 "Eco2.User" user "User.Eco2")
		(25 "Edge.Cuts" user "Board Geometry/Outline")
		(27 "Margin" user)
		(31 "F.CrtYd" user "Package Geometry/Place Bound Top")
		(29 "B.CrtYd" user "Package Geometry/Place Bound Bottom")
		(35 "F.Fab" user "Ref Des/Assembly Top")
		(33 "B.Fab" user "Ref Des/Assembly Bottom")
	)
	(footprint ""
		(layer "F.Cu")
		(at 30.71114 -438.161938 -90)
		(property "Reference" "R3004"
			(at 0 0 270)
			(layer "F.SilkS")
			(hide yes)
			(effects
				(font
					(size 1.27 1.27)
				)
			)
		)
		(property "Value" ""
			(at 0 0 270)
			(layer "F.Fab")
			(effects
				(font
					(size 1.27 1.27)
				)
			)
		)
		(duplicate_pad_numbers_are_jumpers no)
		(fp_line
			(start -0.7874 0.4064)
			(end -0.7874 -0.4064)
			(stroke
				(width 0.1524)
				(type default)
			)
			(layer "F.SilkS")
		)
		(fp_line
			(start 0.7874 0.4064)
			(end -0.7874 0.4064)
			(stroke
				(width 0.1524)
				(type default)
			)
			(layer "F.SilkS")
		)
		(fp_line
			(start -0.7874 -0.4064)
			(end 0.7874 -0.4064)
			(stroke
				(width 0.1524)
				(type default)
			)
			(layer "F.SilkS")
		)
		(fp_line
			(start 0.7874 -0.4064)
			(end 0.7874 0.4064)
			(stroke
				(width 0.1524)
				(type default)
			)
			(layer "F.SilkS")
		)
		(fp_line
			(start -0.67945 0.3048)
			(end -0.67945 -0.305054)
			(stroke
				(width 0.1)
				(type default)
			)
			(layer "F.Fab")
		)
		(fp_line
			(start -0.12065 0.3048)
			(end -0.67945 0.3048)
			(stroke
				(width 0.1)
				(type default)
			)
			(layer "F.Fab")
		)
		(fp_line
			(start 0.120396 0.3048)
			(end 0.120396 0.2794)
			(stroke
				(width 0.1)
				(type default)
			)
			(layer "F.Fab")
		)
		(fp_line
			(start 0.67945 0.3048)
			(end 0.120396 0.3048)
			(stroke
				(width 0.1)
				(type default)
			)
			(layer "F.Fab")
		)
		(fp_line
			(start -0.12065 0.2794)
			(end -0.12065 0.3048)
			(stroke
				(width 0.1)
				(type default)
			)
			(layer "F.Fab")
		)
		(fp_line
			(start 0.120396 0.2794)
			(end -0.12065 0.2794)
			(stroke
				(width 0.1)
				(type default)
			)
			(layer "F.Fab")
		)
		(fp_line
			(start -0.12065 -0.2794)
			(end 0.12065 -0.2794)
			(stroke
				(width 0.1)
				(type default)
			)
			(layer "F.Fab")
		)
		(fp_line
			(start 0.12065 -0.2794)
			(end 0.12065 -0.3048)
			(stroke
				(width 0.1)
				(type default)
			)
			(layer "F.Fab")
		)
		(fp_line
			(start 0.12065 -0.3048)
			(end 0.67945 -0.3048)
			(stroke
				(width 0.1)
				(type default)
			)
			(layer "F.Fab")
		)
		(fp_line
			(start 0.67945 -0.3048)
			(end 0.67945 0.3048)
			(stroke
				(width 0.1)
				(type default)
			)
			(layer "F.Fab")
		)
		(fp_line
			(start -0.67945 -0.305054)
			(end -0.12065 -0.305054)
			(stroke
				(width 0.1)
				(type default)
			)
			(layer "F.Fab")
		)
		(fp_line
			(start -0.12065 -0.305054)
			(end -0.12065 -0.2794)
			(stroke
				(width 0.1)
				(type default)
			)
			(layer "F.Fab")
		)
		(pad "1" smd circle
			(at -0.40005 0 270)
			(size 0 0)
			(layers "F.Cu" "F.Mask" "F.Paste")
			(net "SMB_2_BMC_GPU_SDA")
		)
		(pad "2" smd circle
			(at 0.40005 0 270)
			(size 0 0)
			(layers "F.Cu" "F.Mask" "F.Paste")
			(net "P3V3_AUX")
		)
	)
	(footprint ""
		(layer "F.Cu")
		(at 164.592 -102.199948)
		(property "Reference" "R1756"
			(at 0 0 0)
			(layer "F.SilkS")
			(hide yes)
			(effects
				(font
					(size 1.27 1.27)
				)
			)
		)
		(property "Value" ""
			(at 0 0 0)
			(layer "F.Fab")
			(effects
				(font
					(size 1.27 1.27)
				)
			)
		)
		(duplicate_pad_numbers_are_jumpers no)
		(fp_line
			(start -0.7874 -0.4064)
			(end 0.7874 -0.4064)
			(stroke
				(width 0.1524)
				(type default)
			)
			(layer "F.SilkS")
		)
		(fp_line
			(start -0.7874 0.4064)
			(end -0.7874 -0.4064)
			(stroke
				(width 0.1524)
				(type default)
			)
			(layer "F.SilkS")
		)
		(fp_line
			(start 0.7874 -0.4064)
			(end 0.7874 0.4064)
			(stroke
				(width 0.1524)
				(type default)
			)
			(layer "F.SilkS")
		)
		(fp_line
			(start 0.7874 0.4064)
			(end -0.7874 0.4064)
			(stroke
				(width 0.1524)
				(type default)
			)
			(layer "F.SilkS")
		)
		(fp_line
			(start -0.67945 -0.305054)
			(end -0.12065 -0.305054)
			(stroke
				(width 0.1)
				(type default)
			)
			(layer "F.Fab")
		)
		(fp_line
			(start -0.67945 0.3048)
			(end -0.67945 -0.305054)
			(stroke
				(width 0.1)
				(type default)
			)
			(layer "F.Fab")
		)
		(fp_line
			(start -0.12065 -0.305054)
			(end -0.12065 -0.2794)
			(stroke
				(width 0.1)
				(type default)
			)
			(layer "F.Fab")
		)
		(fp_line
			(start -0.12065 -0.2794)
			(end 0.12065 -0.2794)
			(stroke
				(width 0.1)
				(type default)
			)
			(layer "F.Fab")
		)
		(fp_line
			(start -0.12065 0.2794)
			(end -0.12065 0.3048)
			(stroke
				(width 0.1)
				(type default)
			)
			(layer "F.Fab")
		)
		(fp_line
			(start -0.12065 0.3048)
			(end -0.67945 0.3048)
			(stroke
				(width 0.1)
				(type default)
			)
			(layer "F.Fab")
		)
		(fp_line
			(start 0.120396 0.2794)
			(end -0.12065 0.2794)
			(stroke
				(width 0.1)
				(type default)
			)
			(layer "F.Fab")
		)
		(fp_line
			(start 0.120396 0.3048)
			(end 0.120396 0.2794)
			(stroke
				(width 0.1)
				(type default)
			)
			(layer "F.Fab")
		)
		(fp_line
			(start 0.12065 -0.3048)
			(end 0.67945 -0.3048)
			(stroke
				(width 0.1)
				(type default)
			)
			(layer "F.Fab")
		)
		(fp_line
			(start 0.12065 -0.2794)
			(end 0.12065 -0.3048)
			(stroke
				(width 0.1)
				(type default)
			)
			(layer "F.Fab")
		)
		(fp_line
			(start 0.67945 -0.3048)
			(end 0.67945 0.3048)
			(stroke
				(width 0.1)
				(type default)
			)
			(layer "F.Fab")
		)
		(fp_line
			(start 0.67945 0.3048)
			(end 0.120396 0.3048)
			(stroke
				(width 0.1)
				(type default)
			)
			(layer "F.Fab")
		)
		(pad "1" smd circle
			(at -0.40005 0)
			(size 0 0)
			(layers "F.Cu" "F.Mask" "F.Paste")
			(net "SGPIO_CLK_1")
		)
		(pad "2" smd circle
			(at 0.40005 0)
			(size 0 0)
			(layers "F.Cu" "F.Mask" "F.Paste")
			(net "SGPIO_BMC_CLK")
		)
	)
	(footprint ""
		(layer "F.Cu")
		(at 365.03864 -315.66739 90)
		(property "Reference" "PC316"
			(at 0 0 90)
			(layer "F.SilkS")
			(hide yes)
			(effects
				(font
					(size 1.27 1.27)
				)
			)
		)
		(property "Value" ""
			(at 0 0 90)
			(layer "F.Fab")
			(effects
				(font
					(size 1.27 1.27)
				)
			)
		)
		(duplicate_pad_numbers_are_jumpers no)
		(fp_line
			(start 2.750058 0.999998)
			(end -2.750058 0.999998)
			(stroke
				(width 0.1524)
				(type default)
			)
			(layer "F.SilkS")
		)
		(fp_circle
			(center 0 0.999998)
			(end 0 3.750056)
			(stroke
				(width 0.1524)
				(type default)
			)
			(fill no)
			(layer "F.SilkS")
		)
		(fp_poly
			(pts
				(arc
					(start 2.750058 0.999998)
					(mid 0 3.750056)
					(end -2.750058 0.999998)
				)
			)
			(stroke
				(width 0)
				(type default)
			)
			(fill yes)
			(layer "F.SilkS")
		)
		(fp_circle
			(center 0 0.999998)
			(end 0 3.750056)
			(stroke
				(width 0.1)
				(type default)
			)
			(fill no)
			(layer "F.Fab")
		)
		(pad "1" thru_hole rect
			(at 0 0 90)
			(size 1.5748 1.5748)
			(drill 1.0668)
			(layers "*.Cu" "*.Mask")
			(remove_unused_layers no)
			(net "PVCCIN_CPU0")
			(clearance 0)
			(padstack
				(mode front_inner_back)
				(layer "Inner"
					(shape circle)
					(size 1.5748 1.5748)
					(clearance 0)
				)
				(layer "B.Cu"
					(shape rect)
					(size 1.5748 1.5748)
					(clearance 0)
				)
			)
		)
		(pad "2" thru_hole circle
			(at 0 1.999996 90)
			(size 1.5748 1.5748)
			(drill 1.0668)
			(layers "*.Cu" "*.Mask")
			(remove_unused_layers no)
			(net "GND")
			(clearance 0)
		)
	)
)
